# SCM (Grand Teton) — schematic netlist excerpt (pin names and nets, part order shuffled) for the footprints in the layout excerpt that follows; sources: Cadence DE-HDL packaged netlist, KiCad conversion of 12092022_DA0F0TMDCD0_F0T_Management_Board_D_brd_V3_OCP.brd

R410  Q_RES  49.9 1% CHIP  pkg 0402LF  page 26 : A = SMB_TMP421_BMC_MM2_SCL ; B = SMB_BMC_MM2_SCL
R739  Q_RES  4.7K 1% CHIP  pkg 0402LF  page 28 : A = P3V3_AUX ; B = LED_POSTCODE_A1

(kicad_pcb
	(version 20260206)
	(generator "pcbnew")
	(generator_version "10.0")
	(general
		(thickness 1.6)
		(legacy_teardrops no)
	)
	(paper "A4")
	(title_block
		(title "12092022_DA0F0TMDCD0_F0T_Management_Board_D_brd_V3_OCP.brd")
		(comment 1 "Grand Teton / footprints 1171-1172 of 1440")
	)
	(layers
		(0 "F.Cu" signal "TOP")
		(4 "In1.Cu" signal "GND")
		(6 "In2.Cu" signal "IN1")
		(8 "In3.Cu" signal "GND1")
		(10 "In4.Cu" signal "IN2")
		(12 "In5.Cu" signal "VCC")
		(14 "In6.Cu" signal "VCC1")
		(16 "In7.Cu" signal "IN3")
		(18 "In8.Cu" signal "GND2")
		(20 "In9.Cu" signal "IN4")
		(22 "In10.Cu" signal "GND3")
		(2 "B.Cu" signal "BOTTOM")
		(9 "F.Adhes" user "F.Adhesive")
		(11 "B.Adhes" user "B.Adhesive")
		(13 "F.Paste" user "Package Geometry/Pastemask Top")
		(15 "B.Paste" user "Package Geometry/Pastemask Bottom")
		(5 "F.SilkS" user "Ref Des/Silkscreen Top")
		(7 "B.SilkS" user "Ref Des/Silkscreen Bottom")
		(1 "F.Mask" user "Board Geometry/Soldermask Top")
		(3 "B.Mask" user "Board Geometry/Soldermask Bottom")
		(17 "Dwgs.User" user "User.Drawings")
		(19 "Cmts.User" user "User.Comments")
		(21 "Eco1.User" user "User.Eco1")
		(23 "Eco2.User" user "User.Eco2")
		(25 "Edge.Cuts" user "Board Geometry/Outline")
		(27 "Margin" user)
		(31 "F.CrtYd" user "Package Geometry/Place Bound Top")
		(29 "B.CrtYd" user "Package Geometry/Place Bound Bottom")
		(35 "F.Fab" user "Ref Des/Assembly Top")
		(33 "B.Fab" user "Ref Des/Assembly Bottom")
	)
	(footprint ""
		(layer "B.Cu")
		(at 18.415 -17.907 90)
		(property "Reference" "R410"
			(at 0 0 90)
			(layer "B.SilkS")
			(hide yes)
			(effects
				(font
					(size 1.27 1.27)
				)
				(justify mirror)
			)
		)
		(property "Value" ""
			(at 0 0 90)
			(layer "B.Fab")
			(effects
				(font
					(size 1.27 1.27)
				)
				(justify mirror)
			)
		)
		(duplicate_pad_numbers_are_jumpers no)
		(fp_line
			(start 0.7874 -0.4064)
			(end -0.7874 -0.4064)
			(stroke
				(width 0.1524)
				(type default)
			)
			(layer "B.SilkS")
		)
		(fp_line
			(start -0.7874 -0.4064)
			(end -0.7874 0.4064)
			(stroke
				(width 0.1524)
				(type default)
			)
			(layer "B.SilkS")
		)
		(fp_line
			(start 0.7874 0.4064)
			(end 0.7874 -0.4064)
			(stroke
				(width 0.1524)
				(type default)
			)
			(layer "B.SilkS")
		)
		(fp_line
			(start -0.7874 0.4064)
			(end 0.7874 0.4064)
			(stroke
				(width 0.1524)
				(type default)
			)
			(layer "B.SilkS")
		)
		(fp_line
			(start 0.67945 -0.305054)
			(end 0.12065 -0.305054)
			(stroke
				(width 0.1)
				(type default)
			)
			(layer "B.Fab")
		)
		(fp_line
			(start 0.12065 -0.305054)
			(end 0.12065 -0.2794)
			(stroke
				(width 0.1)
				(type default)
			)
			(layer "B.Fab")
		)
		(fp_line
			(start -0.12065 -0.3048)
			(end -0.67945 -0.3048)
			(stroke
				(width 0.1)
				(type default)
			)
			(layer "B.Fab")
		)
		(fp_line
			(start -0.67945 -0.3048)
			(end -0.67945 0.3048)
			(stroke
				(width 0.1)
				(type default)
			)
			(layer "B.Fab")
		)
		(fp_line
			(start 0.12065 -0.2794)
			(end -0.12065 -0.2794)
			(stroke
				(width 0.1)
				(type default)
			)
			(layer "B.Fab")
		)
		(fp_line
			(start -0.12065 -0.2794)
			(end -0.12065 -0.3048)
			(stroke
				(width 0.1)
				(type default)
			)
			(layer "B.Fab")
		)
		(fp_line
			(start 0.12065 0.2794)
			(end 0.12065 0.3048)
			(stroke
				(width 0.1)
				(type default)
			)
			(layer "B.Fab")
		)
		(fp_line
			(start -0.120396 0.2794)
			(end 0.12065 0.2794)
			(stroke
				(width 0.1)
				(type default)
			)
			(layer "B.Fab")
		)
		(fp_line
			(start 0.67945 0.3048)
			(end 0.67945 -0.305054)
			(stroke
				(width 0.1)
				(type default)
			)
			(layer "B.Fab")
		)
		(fp_line
			(start 0.12065 0.3048)
			(end 0.67945 0.3048)
			(stroke
				(width 0.1)
				(type default)
			)
			(layer "B.Fab")
		)
		(fp_line
			(start -0.120396 0.3048)
			(end -0.120396 0.2794)
			(stroke
				(width 0.1)
				(type default)
			)
			(layer "B.Fab")
		)
		(fp_line
			(start -0.67945 0.3048)
			(end -0.120396 0.3048)
			(stroke
				(width 0.1)
				(type default)
			)
			(layer "B.Fab")
		)
		(pad "1" smd circle
			(at 0.40005 0 270)
			(size 0 0)
			(layers "B.Cu" "B.Mask" "B.Paste")
			(net "SMB_TMP421_BMC_MM2_SCL")
		)
		(pad "2" smd circle
			(at -0.40005 0 270)
			(size 0 0)
			(layers "B.Cu" "B.Mask" "B.Paste")
			(net "SMB_BMC_MM2_SCL")
		)
	)
	(footprint ""
		(layer "B.Cu")
		(at 63.9572 -91.2114)
		(property "Reference" "R739"
			(at 0 0 0)
			(layer "B.SilkS")
			(hide yes)
			(effects
				(font
					(size 1.27 1.27)
				)
				(justify mirror)
			)
		)
		(property "Value" ""
			(at 0 0 0)
			(layer "B.Fab")
			(effects
				(font
					(size 1.27 1.27)
				)
				(justify mirror)
			)
		)
		(duplicate_pad_numbers_are_jumpers no)
		(fp_line
			(start -0.7874 -0.4064)
			(end -0.7874 0.4064)
			(stroke
				(width 0.1524)
				(type default)
			)
			(layer "B.SilkS")
		)
		(fp_line
			(start -0.7874 0.4064)
			(end 0.7874 0.4064)
			(stroke
				(width 0.1524)
				(type default)
			)
			(layer "B.SilkS")
		)
		(fp_line
			(start 0.7874 -0.4064)
			(end -0.7874 -0.4064)
			(stroke
				(width 0.1524)
				(type default)
			)
			(layer "B.SilkS")
		)
		(fp_line
			(start 0.7874 0.4064)
			(end 0.7874 -0.4064)
			(stroke
				(width 0.1524)
				(type default)
			)
			(layer "B.SilkS")
		)
		(fp_line
			(start -0.67945 -0.3048)
			(end -0.67945 0.3048)
			(stroke
				(width 0.1)
				(type default)
			)
			(layer "B.Fab")
		)
		(fp_line
			(start -0.67945 0.3048)
			(end -0.120396 0.3048)
			(stroke
				(width 0.1)
				(type default)
			)
			(layer "B.Fab")
		)
		(fp_line
			(start -0.12065 -0.3048)
			(end -0.67945 -0.3048)
			(stroke
				(width 0.1)
				(type default)
			)
			(layer "B.Fab")
		)
		(fp_line
			(start -0.12065 -0.2794)
			(end -0.12065 -0.3048)
			(stroke
				(width 0.1)
				(type default)
			)
			(layer "B.Fab")
		)
		(fp_line
			(start -0.120396 0.2794)
			(end 0.12065 0.2794)
			(stroke
				(width 0.1)
				(type default)
			)
			(layer "B.Fab")
		)
		(fp_line
			(start -0.120396 0.3048)
			(end -0.120396 0.2794)
			(stroke
				(width 0.1)
				(type default)
			)
			(layer "B.Fab")
		)
		(fp_line
			(start 0.12065 -0.305054)
			(end 0.12065 -0.2794)
			(stroke
				(width 0.1)
				(type default)
			)
			(layer "B.Fab")
		)
		(fp_line
			(start 0.12065 -0.2794)
			(end -0.12065 -0.2794)
			(stroke
				(width 0.1)
				(type default)
			)
			(layer "B.Fab")
		)
		(fp_line
			(start 0.12065 0.2794)
			(end 0.12065 0.3048)
			(stroke
				(width 0.1)
				(type default)
			)
			(layer "B.Fab")
		)
		(fp_line
			(start 0.12065 0.3048)
			(end 0.67945 0.3048)
			(stroke
				(width 0.1)
				(type default)
			)
			(layer "B.Fab")
		)
		(fp_line
			(start 0.67945 -0.305054)
			(end 0.12065 -0.305054)
			(stroke
				(width 0.1)
				(type default)
			)
			(layer "B.Fab")
		)
		(fp_line
			(start 0.67945 0.3048)
			(end 0.67945 -0.305054)
			(stroke
				(width 0.1)
				(type default)
			)
			(layer "B.Fab")
		)
		(pad "1" smd circle
			(at 0.40005 0 180)
			(size 0 0)
			(layers "B.Cu" "B.Mask" "B.Paste")
			(net "P3V3_AUX")
		)
		(pad "2" smd circle
			(at -0.40005 0 180)
			(size 0 0)
			(layers "B.Cu" "B.Mask" "B.Paste")
			(net "LED_POSTCODE_A1")
		)
	)
)
